FILE_TYPE = CONNECTIVITY;
{Allegro Design Entry HDL 17.2-2016 S067 (3860444) 4/26/2020}
"PAGE_NUMBER" = 18;
0"NC";
END.
